# S9S_MB_2U (Grand Teton) — schematic netlist excerpt (pin names and nets, part order shuffled) for the footprints in the layout excerpt that follows; sources: Cadence DE-HDL packaged netlist, KiCad conversion of 03242023_DA0F0TMBIJ0_F0T_Motherboard_J_brd_V01_OCP.brd

R4558  Q_RES  33.2 1% CHIP  pkg 0402LF  page 215 : A = SWB_HSC_EN ; B = SWB_HSC_EN_R
R4555  Q_RES  4.7K 5% EMPTY  pkg 0402LF  page 145 : A = SWB_HSC_EN_BUF_R ; B = GND

(kicad_pcb
	(version 20260206)
	(generator "pcbnew")
	(generator_version "10.0")
	(general
		(thickness 1.6)
		(legacy_teardrops no)
	)
	(paper "A4")
	(title_block
		(title "03242023_DA0F0TMBIJ0_F0T_Motherboard_J_brd_V01_OCP.brd")
		(comment 1 "Grand Teton / footprints 3452-3453 of 6105")
	)
	(layers
		(0 "F.Cu" signal "TOP")
		(4 "In1.Cu" signal "GND")
		(6 "In2.Cu" signal "IN1")
		(8 "In3.Cu" signal "GND1")
		(10 "In4.Cu" signal "IN2")
		(12 "In5.Cu" signal "GND2")
		(14 "In6.Cu" signal "IN3")
		(16 "In7.Cu" signal "GND3")
		(18 "In8.Cu" signal "VCC")
		(20 "In9.Cu" signal "VCC1")
		(22 "In10.Cu" signal "GND4")
		(24 "In11.Cu" signal "IN4")
		(26 "In12.Cu" signal "GND5")
		(28 "In13.Cu" signal "IN5")
		(30 "In14.Cu" signal "GND6")
		(32 "In15.Cu" signal "IN6")
		(34 "In16.Cu" signal "GND7")
		(2 "B.Cu" signal "BOTTOM")
		(9 "F.Adhes" user "F.Adhesive")
		(11 "B.Adhes" user "B.Adhesive")
		(13 "F.Paste" user "Package Geometry/Pastemask Top")
		(15 "B.Paste" user "Package Geometry/Pastemask Bottom")
		(5 "F.SilkS" user "Ref Des/Silkscreen Top")
		(7 "B.SilkS" user "Ref Des/Silkscreen Bottom")
		(1 "F.Mask" user "Board Geometry/Soldermask Top")
		(3 "B.Mask" user "Board Geometry/Soldermask Bottom")
		(17 "Dwgs.User" user "User.Drawings")
		(19 "Cmts.User" user "User.Comments")
		(21 "Eco1.User" user "User.Eco1")
		(23 "Eco2.User" user "User.Eco2")
		(25 "Edge.Cuts" user "Board Geometry/Outline")
		(27 "Margin" user)
		(31 "F.CrtYd" user "Package Geometry/Place Bound Top")
		(29 "B.CrtYd" user "Package Geometry/Place Bound Bottom")
		(35 "F.Fab" user "Ref Des/Assembly Top")
		(33 "B.Fab" user "Ref Des/Assembly Bottom")
	)
	(footprint ""
		(layer "F.Cu")
		(at 354.8126 -408.818588 180)
		(property "Reference" "R4558"
			(at 0 0 180)
			(layer "F.SilkS")
			(hide yes)
			(effects
				(font
					(size 1.27 1.27)
				)
			)
		)
		(property "Value" ""
			(at 0 0 180)
			(layer "F.Fab")
			(effects
				(font
					(size 1.27 1.27)
				)
			)
		)
		(duplicate_pad_numbers_are_jumpers no)
		(fp_line
			(start 0.7874 0.4064)
			(end -0.7874 0.4064)
			(stroke
				(width 0.1524)
				(type default)
			)
			(layer "F.SilkS")
		)
		(fp_line
			(start 0.7874 -0.4064)
			(end 0.7874 0.4064)
			(stroke
				(width 0.1524)
				(type default)
			)
			(layer "F.SilkS")
		)
		(fp_line
			(start -0.7874 0.4064)
			(end -0.7874 -0.4064)
			(stroke
				(width 0.1524)
				(type default)
			)
			(layer "F.SilkS")
		)
		(fp_line
			(start -0.7874 -0.4064)
			(end 0.7874 -0.4064)
			(stroke
				(width 0.1524)
				(type default)
			)
			(layer "F.SilkS")
		)
		(fp_line
			(start 0.67945 0.3048)
			(end 0.120396 0.3048)
			(stroke
				(width 0.1)
				(type default)
			)
			(layer "F.Fab")
		)
		(fp_line
			(start 0.67945 -0.3048)
			(end 0.67945 0.3048)
			(stroke
				(width 0.1)
				(type default)
			)
			(layer "F.Fab")
		)
		(fp_line
			(start 0.12065 -0.2794)
			(end 0.12065 -0.3048)
			(stroke
				(width 0.1)
				(type default)
			)
			(layer "F.Fab")
		)
		(fp_line
			(start 0.12065 -0.3048)
			(end 0.67945 -0.3048)
			(stroke
				(width 0.1)
				(type default)
			)
			(layer "F.Fab")
		)
		(fp_line
			(start 0.120396 0.3048)
			(end 0.120396 0.2794)
			(stroke
				(width 0.1)
				(type default)
			)
			(layer "F.Fab")
		)
		(fp_line
			(start 0.120396 0.2794)
			(end -0.12065 0.2794)
			(stroke
				(width 0.1)
				(type default)
			)
			(layer "F.Fab")
		)
		(fp_line
			(start -0.12065 0.3048)
			(end -0.67945 0.3048)
			(stroke
				(width 0.1)
				(type default)
			)
			(layer "F.Fab")
		)
		(fp_line
			(start -0.12065 0.2794)
			(end -0.12065 0.3048)
			(stroke
				(width 0.1)
				(type default)
			)
			(layer "F.Fab")
		)
		(fp_line
			(start -0.12065 -0.2794)
			(end 0.12065 -0.2794)
			(stroke
				(width 0.1)
				(type default)
			)
			(layer "F.Fab")
		)
		(fp_line
			(start -0.12065 -0.305054)
			(end -0.12065 -0.2794)
			(stroke
				(width 0.1)
				(type default)
			)
			(layer "F.Fab")
		)
		(fp_line
			(start -0.67945 0.3048)
			(end -0.67945 -0.305054)
			(stroke
				(width 0.1)
				(type default)
			)
			(layer "F.Fab")
		)
		(fp_line
			(start -0.67945 -0.305054)
			(end -0.12065 -0.305054)
			(stroke
				(width 0.1)
				(type default)
			)
			(layer "F.Fab")
		)
		(pad "1" smd circle
			(at -0.40005 0 180)
			(size 0 0)
			(layers "F.Cu" "F.Mask" "F.Paste")
			(net "SWB_HSC_EN")
		)
		(pad "2" smd circle
			(at 0.40005 0 180)
			(size 0 0)
			(layers "F.Cu" "F.Mask" "F.Paste")
			(net "SWB_HSC_EN_R")
		)
	)
	(footprint ""
		(layer "F.Cu")
		(at 362.14558 -408.544268)
		(property "Reference" "R4555"
			(at 0 0 0)
			(layer "F.SilkS")
			(hide yes)
			(effects
				(font
					(size 1.27 1.27)
				)
			)
		)
		(property "Value" ""
			(at 0 0 0)
			(layer "F.Fab")
			(effects
				(font
					(size 1.27 1.27)
				)
			)
		)
		(duplicate_pad_numbers_are_jumpers no)
		(fp_line
			(start -0.7874 -0.4064)
			(end 0.7874 -0.4064)
			(stroke
				(width 0.1524)
				(type default)
			)
			(layer "F.SilkS")
		)
		(fp_line
			(start -0.7874 0.4064)
			(end -0.7874 -0.4064)
			(stroke
				(width 0.1524)
				(type default)
			)
			(layer "F.SilkS")
		)
		(fp_line
			(start 0.7874 -0.4064)
			(end 0.7874 0.4064)
			(stroke
				(width 0.1524)
				(type default)
			)
			(layer "F.SilkS")
		)
		(fp_line
			(start 0.7874 0.4064)
			(end -0.7874 0.4064)
			(stroke
				(width 0.1524)
				(type default)
			)
			(layer "F.SilkS")
		)
		(fp_line
			(start -0.67945 -0.305054)
			(end -0.12065 -0.305054)
			(stroke
				(width 0.1)
				(type default)
			)
			(layer "F.Fab")
		)
		(fp_line
			(start -0.67945 0.3048)
			(end -0.67945 -0.305054)
			(stroke
				(width 0.1)
				(type default)
			)
			(layer "F.Fab")
		)
		(fp_line
			(start -0.12065 -0.305054)
			(end -0.12065 -0.2794)
			(stroke
				(width 0.1)
				(type default)
			)
			(layer "F.Fab")
		)
		(fp_line
			(start -0.12065 -0.2794)
			(end 0.12065 -0.2794)
			(stroke
				(width 0.1)
				(type default)
			)
			(layer "F.Fab")
		)
		(fp_line
			(start -0.12065 0.2794)
			(end -0.12065 0.3048)
			(stroke
				(width 0.1)
				(type default)
			)
			(layer "F.Fab")
		)
		(fp_line
			(start -0.12065 0.3048)
			(end -0.67945 0.3048)
			(stroke
				(width 0.1)
				(type default)
			)
			(layer "F.Fab")
		)
		(fp_line
			(start 0.120396 0.2794)
			(end -0.12065 0.2794)
			(stroke
				(width 0.1)
				(type default)
			)
			(layer "F.Fab")
		)
		(fp_line
			(start 0.120396 0.3048)
			(end 0.120396 0.2794)
			(stroke
				(width 0.1)
				(type default)
			)
			(layer "F.Fab")
		)
		(fp_line
			(start 0.12065 -0.3048)
			(end 0.67945 -0.3048)
			(stroke
				(width 0.1)
				(type default)
			)
			(layer "F.Fab")
		)
		(fp_line
			(start 0.12065 -0.2794)
			(end 0.12065 -0.3048)
			(stroke
				(width 0.1)
				(type default)
			)
			(layer "F.Fab")
		)
		(fp_line
			(start 0.67945 -0.3048)
			(end 0.67945 0.3048)
			(stroke
				(width 0.1)
				(type default)
			)
			(layer "F.Fab")
		)
		(fp_line
			(start 0.67945 0.3048)
			(end 0.120396 0.3048)
			(stroke
				(width 0.1)
				(type default)
			)
			(layer "F.Fab")
		)
		(pad "1" smd circle
			(at -0.40005 0)
			(size 0 0)
			(layers "F.Cu" "F.Mask" "F.Paste")
			(net "SWB_HSC_EN_BUF_R")
		)
		(pad "2" smd circle
			(at 0.40005 0)
			(size 0 0)
			(layers "F.Cu" "F.Mask" "F.Paste")
			(net "GND")
		)
	)
)
